(kicad_pcb
	(version 20241229)
	(generator "pcbnew")
	(generator_version "9.0")
	(general
		(thickness 1.6642)
		(legacy_teardrops no)
	)
	(paper "A3")
	(title_block
		(title "PolarFire SoM")
		(date "2025-07-22")
		(rev "1.1.4")
		(company "Antmicro Ltd")
		(comment 1 "www.antmicro.com")
		(comment 9 "footprints 200-204 of 470")
	)
	(layers
		(0 "F.Cu" mixed)
		(4 "In1.Cu" power)
		(6 "In2.Cu" signal)
		(8 "In3.Cu" power)
		(10 "In4.Cu" signal)
		(12 "In5.Cu" power)
		(14 "In6.Cu" power)
		(16 "In7.Cu" signal)
		(18 "In8.Cu" power)
		(20 "In9.Cu" signal)
		(22 "In10.Cu" power)
		(24 "In11.Cu" signal)
		(26 "In12.Cu" signal)
		(2 "B.Cu" mixed)
		(9 "F.Adhes" user "F.Adhesive")
		(11 "B.Adhes" user "B.Adhesive")
		(13 "F.Paste" user)
		(15 "B.Paste" user)
		(5 "F.SilkS" user "F.Silkscreen")
		(7 "B.SilkS" user "B.Silkscreen")
		(1 "F.Mask" user)
		(3 "B.Mask" user)
		(17 "Dwgs.User" user "User.Drawings")
		(19 "Cmts.User" user "User.Comments")
		(21 "Eco1.User" user "User.Eco1")
		(23 "Eco2.User" user "User.Eco2")
		(25 "Edge.Cuts" user)
		(27 "Margin" user)
		(31 "F.CrtYd" user "F.Courtyard")
		(29 "B.CrtYd" user "B.Courtyard")
		(35 "F.Fab" user)
		(33 "B.Fab" user)
	)
	(footprint "antmicro-footprints:R_0402_1005Metric"
		(layer "B.Cu")
		(at 210.1775 134.347)
		(descr "Resistor SMD 0402")
		(tags "resistor SMD 0402")
		(property "Reference" "R28"
			(at 1.6225 3.353 180)
			(layer "B.SilkS")
			(effects
				(font
					(size 0.7 0.7)
					(thickness 0.15)
				)
				(justify left bottom mirror)
			)
		)
		(property "Value" "R_10k_0402"
			(at -1.011843 -1.772047 180)
			(layer "B.Fab")
			(hide yes)
			(effects
				(font
					(size 0.7 0.7)
					(thickness 0.15)
				)
				(justify left bottom mirror)
			)
		)
		(property "Datasheet" "https://www.bourns.com/docs/product-datasheets/cr.pdf"
			(at 0 0 0)
			(layer "F.Fab")
			(hide yes)
			(effects
				(font
					(size 1.27 1.27)
					(thickness 0.15)
				)
			)
		)
		(property "Description" "SMD Chip Resistor, 10 kohm, ± 1%, 62.5 mW, 0402 [1005 Metric], Thick Film, General Purpose"
			(at 0 0 0)
			(layer "F.Fab")
			(hide yes)
			(effects
				(font
					(size 1.27 1.27)
					(thickness 0.15)
				)
			)
		)
		(property "Author" "Antmicro"
			(at 0 0 0)
			(layer "B.Fab")
			(hide yes)
			(effects
				(font
					(size 1 1)
					(thickness 0.15)
				)
				(justify mirror)
			)
		)
		(property "License" "Apache-2.0"
			(at 0 0 0)
			(layer "B.Fab")
			(hide yes)
			(effects
				(font
					(size 1 1)
					(thickness 0.15)
				)
				(justify mirror)
			)
		)
		(property "MPN" "CR0402-FX-1002GLF"
			(at 0 0 0)
			(layer "B.Fab")
			(hide yes)
			(effects
				(font
					(size 1 1)
					(thickness 0.15)
				)
				(justify mirror)
			)
		)
		(property "Manufacturer" "Bourns"
			(at 0 0 0)
			(layer "B.Fab")
			(hide yes)
			(effects
				(font
					(size 1 1)
					(thickness 0.15)
				)
				(justify mirror)
			)
		)
		(property "Public" ""
			(at 0 0 0)
			(layer "B.Fab")
			(hide yes)
			(effects
				(font
					(size 1 1)
					(thickness 0.15)
				)
				(justify mirror)
			)
		)
		(property "Tolerance" "1%"
			(at 0 0 0)
			(layer "B.Fab")
			(hide yes)
			(effects
				(font
					(size 1 1)
					(thickness 0.15)
				)
				(justify mirror)
			)
		)
		(property "Val" "10k"
			(at 0 0 0)
			(layer "B.Fab")
			(hide yes)
			(effects
				(font
					(size 1 1)
					(thickness 0.15)
				)
				(justify mirror)
			)
		)
		(sheetname "/Memory/")
		(sheetfile "memory.kicad_sch")
		(attr smd)
		(fp_rect
			(start -0.925 0.47)
			(end 0.925 -0.47)
			(stroke
				(width 0.05)
				(type default)
			)
			(fill no)
			(layer "B.CrtYd")
		)
		(fp_rect
			(start -0.5 0.25)
			(end 0.5 -0.25)
			(stroke
				(width 0.15)
				(type solid)
			)
			(fill no)
			(layer "B.Fab")
		)
		(fp_text user "License: Apache-2.0"
			(at -0.95 -5.169 180)
			(layer "B.Fab")
			(effects
				(font
					(size 0.7 0.7)
					(thickness 0.15)
				)
				(justify left bottom mirror)
			)
		)
		(fp_text user "Author: Antmicro"
			(at -0.95 -4.169 180)
			(layer "B.Fab")
			(effects
				(font
					(size 0.7 0.7)
					(thickness 0.15)
				)
				(justify left bottom mirror)
			)
		)
		(fp_text user "${REFERENCE}"
			(at -0.95 -3.168 180)
			(layer "B.Fab")
			(effects
				(font
					(size 0.7 0.7)
					(thickness 0.15)
				)
				(justify left bottom mirror)
			)
		)
		(pad "1" smd roundrect
			(at -0.48 0)
			(size 0.59 0.64)
			(layers "B.Cu" "B.Mask" "B.Paste")
			(roundrect_rratio 0.25)
			(net 387 "/FPGA MSSIO/EMMC.RST_n")
			(pintype "passive")
		)
		(pad "2" smd roundrect
			(at 0.48 0)
			(size 0.59 0.64)
			(layers "B.Cu" "B.Mask" "B.Paste")
			(roundrect_rratio 0.25)
			(net 137 "SD_VDD")
			(pintype "passive")
		)
	)
	(footprint "antmicro-footprints:C_0402_1005Metric"
		(layer "B.Cu")
		(at 196.65 140.55 90)
		(descr "Capacitor SMD 0402")
		(tags "capacitor SMD 0402")
		(property "Reference" "C35"
			(at 1.45 -2.47 270)
			(layer "B.SilkS")
			(effects
				(font
					(size 0.7 0.7)
					(thickness 0.15)
				)
				(justify left bottom mirror)
			)
		)
		(property "Value" "C_100n_0402"
			(at -1.022927 -2.155213 270)
			(layer "B.Fab")
			(hide yes)
			(effects
				(font
					(size 0.7 0.7)
					(thickness 0.15)
				)
				(justify left bottom mirror)
			)
		)
		(property "Datasheet" "https://www.murata.com/products/productdetail?partno=GRM155R61H104KE14%23"
			(at 0 0 90)
			(layer "F.Fab")
			(hide yes)
			(effects
				(font
					(size 1.27 1.27)
					(thickness 0.15)
				)
			)
		)
		(property "Description" "SMD Multilayer Ceramic Capacitor, 0.1 µF, 50 V, 0402 [1005 Metric], ± 10%, X5R, GRM Series"
			(at 0 0 90)
			(layer "F.Fab")
			(hide yes)
			(effects
				(font
					(size 1.27 1.27)
					(thickness 0.15)
				)
			)
		)
		(property "Author" "Antmicro"
			(at 337.2 -56.1 0)
			(layer "B.Fab")
			(hide yes)
			(effects
				(font
					(size 1 1)
					(thickness 0.15)
				)
				(justify mirror)
			)
		)
		(property "Dielectric" "X5R"
			(at 337.2 -56.1 0)
			(layer "B.Fab")
			(hide yes)
			(effects
				(font
					(size 1 1)
					(thickness 0.15)
				)
				(justify mirror)
			)
		)
		(property "License" "Apache-2.0"
			(at 337.2 -56.1 0)
			(layer "B.Fab")
			(hide yes)
			(effects
				(font
					(size 1 1)
					(thickness 0.15)
				)
				(justify mirror)
			)
		)
		(property "MPN" "GRM155R61H104KE14D"
			(at 337.2 -56.1 0)
			(layer "B.Fab")
			(hide yes)
			(effects
				(font
					(size 1 1)
					(thickness 0.15)
				)
				(justify mirror)
			)
		)
		(property "Manufacturer" "Murata"
			(at 337.2 -56.1 0)
			(layer "B.Fab")
			(hide yes)
			(effects
				(font
					(size 1 1)
					(thickness 0.15)
				)
				(justify mirror)
			)
		)
		(property "Public" ""
			(at 337.2 -56.1 0)
			(layer "B.Fab")
			(hide yes)
			(effects
				(font
					(size 1 1)
					(thickness 0.15)
				)
				(justify mirror)
			)
		)
		(property "Val" "100n"
			(at 337.2 -56.1 0)
			(layer "B.Fab")
			(hide yes)
			(effects
				(font
					(size 1 1)
					(thickness 0.15)
				)
				(justify mirror)
			)
		)
		(property "Voltage" "50V"
			(at 337.2 -56.1 0)
			(layer "B.Fab")
			(hide yes)
			(effects
				(font
					(size 1 1)
					(thickness 0.15)
				)
				(justify mirror)
			)
		)
		(sheetname "/FPGA Supply/")
		(sheetfile "fpga-supply.kicad_sch")
		(attr smd)
		(fp_rect
			(start -0.925 0.47)
			(end 0.925 -0.47)
			(stroke
				(width 0.05)
				(type default)
			)
			(fill no)
			(layer "B.CrtYd")
		)
		(fp_line
			(start 0.504 -0.248)
			(end -0.494 -0.248)
			(stroke
				(width 0.15)
				(type solid)
			)
			(layer "B.Fab")
		)
		(fp_line
			(start -0.494 -0.248)
			(end -0.494 0.25)
			(stroke
				(width 0.15)
				(type solid)
			)
			(layer "B.Fab")
		)
		(fp_line
			(start 0.504 0.25)
			(end 0.504 -0.248)
			(stroke
				(width 0.15)
				(type solid)
			)
			(layer "B.Fab")
		)
		(fp_line
			(start -0.494 0.25)
			(end 0.504 0.25)
			(stroke
				(width 0.15)
				(type solid)
			)
			(layer "B.Fab")
		)
		(fp_text user "${REFERENCE}"
			(at -0.939 -4.599 270)
			(layer "B.Fab")
			(effects
				(font
					(size 0.7 0.7)
					(thickness 0.15)
				)
				(justify left bottom mirror)
			)
		)
		(fp_text user "Author: Antmicro"
			(at -0.939 -3.399 270)
			(layer "B.Fab")
			(effects
				(font
					(size 0.7 0.7)
					(thickness 0.15)
				)
				(justify left bottom mirror)
			)
		)
		(fp_text user "License: Apache-2.0"
			(at -0.939 -5.799 270)
			(layer "B.Fab")
			(effects
				(font
					(size 0.7 0.7)
					(thickness 0.15)
				)
				(justify left bottom mirror)
			)
		)
		(pad "1" smd roundrect
			(at -0.48 0 90)
			(size 0.59 0.64)
			(layers "B.Cu" "B.Mask" "B.Paste")
			(roundrect_rratio 0.25)
			(net 417 "GND")
			(pintype "passive")
		)
		(pad "2" smd roundrect
			(at 0.48 0 90)
			(size 0.59 0.64)
			(layers "B.Cu" "B.Mask" "B.Paste")
			(roundrect_rratio 0.25)
			(net 47 "+1V05")
			(pintype "passive")
		)
	)
	(footprint "antmicro-footprints:C_0402_1005Metric"
		(layer "B.Cu")
		(at 212.1925 132.697)
		(descr "Capacitor SMD 0402")
		(tags "capacitor SMD 0402")
		(property "Reference" "C80"
			(at 0.8175 0.913 135)
			(layer "B.SilkS")
			(effects
				(font
					(size 0.7 0.7)
					(thickness 0.15)
				)
				(justify right bottom mirror)
			)
		)
		(property "Value" "C_10u_0402"
			(at -1.022927 -2.155213 0)
			(layer "B.Fab")
			(hide yes)
			(effects
				(font
					(size 0.7 0.7)
					(thickness 0.15)
				)
				(justify right bottom mirror)
			)
		)
		(property "Datasheet" "https://www.yageo.com/en/Chart/Download/pdf/CC0402MRX5R5BB106"
			(at 0 0 0)
			(layer "F.Fab")
			(hide yes)
			(effects
				(font
					(size 1.27 1.27)
					(thickness 0.15)
				)
			)
		)
		(property "Description" "SMD Multilayer Ceramic Capacitor, 10 µF, 6.3 V, 0402 [1005 Metric], ± 20%, X5R, CC Series"
			(at 0 0 0)
			(layer "F.Fab")
			(hide yes)
			(effects
				(font
					(size 1.27 1.27)
					(thickness 0.15)
				)
			)
		)
		(property "Author" "Antmicro"
			(at 0 0 0)
			(layer "B.Fab")
			(hide yes)
			(effects
				(font
					(size 1 1)
					(thickness 0.15)
				)
				(justify mirror)
			)
		)
		(property "Dielectric" ""
			(at 0 0 0)
			(layer "B.Fab")
			(hide yes)
			(effects
				(font
					(size 1 1)
					(thickness 0.15)
				)
				(justify mirror)
			)
		)
		(property "License" "Apache-2.0"
			(at 0 0 0)
			(layer "B.Fab")
			(hide yes)
			(effects
				(font
					(size 1 1)
					(thickness 0.15)
				)
				(justify mirror)
			)
		)
		(property "MPN" "CC0402MRX5R5BB106"
			(at 0 0 0)
			(layer "B.Fab")
			(hide yes)
			(effects
				(font
					(size 1 1)
					(thickness 0.15)
				)
				(justify mirror)
			)
		)
		(property "Manufacturer" "YAGEO"
			(at 0 0 0)
			(layer "B.Fab")
			(hide yes)
			(effects
				(font
					(size 1 1)
					(thickness 0.15)
				)
				(justify mirror)
			)
		)
		(property "Public" ""
			(at 0 0 0)
			(layer "B.Fab")
			(hide yes)
			(effects
				(font
					(size 1 1)
					(thickness 0.15)
				)
				(justify mirror)
			)
		)
		(property "Val" "10u"
			(at 0 0 0)
			(layer "B.Fab")
			(hide yes)
			(effects
				(font
					(size 1 1)
					(thickness 0.15)
				)
				(justify mirror)
			)
		)
		(property "Voltage" ""
			(at 0 0 0)
			(layer "B.Fab")
			(hide yes)
			(effects
				(font
					(size 1 1)
					(thickness 0.15)
				)
				(justify mirror)
			)
		)
		(sheetname "/Memory/")
		(sheetfile "memory.kicad_sch")
		(attr smd)
		(fp_rect
			(start -0.925 0.47)
			(end 0.925 -0.47)
			(stroke
				(width 0.05)
				(type default)
			)
			(fill no)
			(layer "B.CrtYd")
		)
		(fp_line
			(start -0.494 -0.248)
			(end -0.494 0.25)
			(stroke
				(width 0.15)
				(type solid)
			)
			(layer "B.Fab")
		)
		(fp_line
			(start -0.494 0.25)
			(end 0.504 0.25)
			(stroke
				(width 0.15)
				(type solid)
			)
			(layer "B.Fab")
		)
		(fp_line
			(start 0.504 -0.248)
			(end -0.494 -0.248)
			(stroke
				(width 0.15)
				(type solid)
			)
			(layer "B.Fab")
		)
		(fp_line
			(start 0.504 0.25)
			(end 0.504 -0.248)
			(stroke
				(width 0.15)
				(type solid)
			)
			(layer "B.Fab")
		)
		(fp_text user "Author: Antmicro"
			(at -0.939 -3.399 180)
			(layer "B.Fab")
			(effects
				(font
					(size 0.7 0.7)
					(thickness 0.15)
				)
				(justify left bottom mirror)
			)
		)
		(fp_text user "${REFERENCE}"
			(at -0.939 -4.599 180)
			(layer "B.Fab")
			(effects
				(font
					(size 0.7 0.7)
					(thickness 0.15)
				)
				(justify left bottom mirror)
			)
		)
		(fp_text user "License: Apache-2.0"
			(at -0.939 -5.799 180)
			(layer "B.Fab")
			(effects
				(font
					(size 0.7 0.7)
					(thickness 0.15)
				)
				(justify left bottom mirror)
			)
		)
		(pad "1" smd roundrect
			(at -0.48 0)
			(size 0.59 0.64)
			(layers "B.Cu" "B.Mask" "B.Paste")
			(roundrect_rratio 0.25)
			(net 417 "GND")
			(pintype "passive")
		)
		(pad "2" smd roundrect
			(at 0.48 0)
			(size 0.59 0.64)
			(layers "B.Cu" "B.Mask" "B.Paste")
			(roundrect_rratio 0.25)
			(net 137 "SD_VDD")
			(pintype "passive")
		)
	)
	(footprint "antmicro-footprints:R_0402_1005Metric"
		(layer "B.Cu")
		(at 206.15 142.6 180)
		(descr "Resistor SMD 0402")
		(tags "resistor SMD 0402")
		(property "Reference" "R117"
			(at -0.3 -1.34 0)
			(layer "B.SilkS")
			(effects
				(font
					(size 0.7 0.7)
					(thickness 0.15)
				)
				(justify left bottom mirror)
			)
		)
		(property "Value" "R_10k_0402"
			(at -1.011843 -1.772047 0)
			(layer "B.Fab")
			(hide yes)
			(effects
				(font
					(size 0.7 0.7)
					(thickness 0.15)
				)
				(justify left bottom mirror)
			)
		)
		(property "Datasheet" "https://www.bourns.com/docs/product-datasheets/cr.pdf"
			(at 0 0 180)
			(layer "F.Fab")
			(hide yes)
			(effects
				(font
					(size 1.27 1.27)
					(thickness 0.15)
				)
			)
		)
		(property "Description" "SMD Chip Resistor, 10 kohm, ± 1%, 62.5 mW, 0402 [1005 Metric], Thick Film, General Purpose"
			(at 0 0 180)
			(layer "F.Fab")
			(hide yes)
			(effects
				(font
					(size 1.27 1.27)
					(thickness 0.15)
				)
			)
		)
		(property "Author" "Antmicro"
			(at 412.3 285.2 0)
			(layer "B.Fab")
			(hide yes)
			(effects
				(font
					(size 1 1)
					(thickness 0.15)
				)
				(justify mirror)
			)
		)
		(property "License" "Apache-2.0"
			(at 412.3 285.2 0)
			(layer "B.Fab")
			(hide yes)
			(effects
				(font
					(size 1 1)
					(thickness 0.15)
				)
				(justify mirror)
			)
		)
		(property "MPN" "CR0402-FX-1002GLF"
			(at 412.3 285.2 0)
			(layer "B.Fab")
			(hide yes)
			(effects
				(font
					(size 1 1)
					(thickness 0.15)
				)
				(justify mirror)
			)
		)
		(property "Manufacturer" "Bourns"
			(at 412.3 285.2 0)
			(layer "B.Fab")
			(hide yes)
			(effects
				(font
					(size 1 1)
					(thickness 0.15)
				)
				(justify mirror)
			)
		)
		(property "Public" ""
			(at 412.3 285.2 0)
			(layer "B.Fab")
			(hide yes)
			(effects
				(font
					(size 1 1)
					(thickness 0.15)
				)
				(justify mirror)
			)
		)
		(property "Tolerance" "1%"
			(at 412.3 285.2 0)
			(layer "B.Fab")
			(hide yes)
			(effects
				(font
					(size 1 1)
					(thickness 0.15)
				)
				(justify mirror)
			)
		)
		(property "Val" "10k"
			(at 412.3 285.2 0)
			(layer "B.Fab")
			(hide yes)
			(effects
				(font
					(size 1 1)
					(thickness 0.15)
				)
				(justify mirror)
			)
		)
		(sheetname "/MIPI CrossLink/")
		(sheetfile "crosslink.kicad_sch")
		(attr smd)
		(fp_rect
			(start -0.925 0.47)
			(end 0.925 -0.47)
			(stroke
				(width 0.05)
				(type default)
			)
			(fill no)
			(layer "B.CrtYd")
		)
		(fp_rect
			(start -0.5 0.25)
			(end 0.5 -0.25)
			(stroke
				(width 0.15)
				(type solid)
			)
			(fill no)
			(layer "B.Fab")
		)
		(fp_text user "Author: Antmicro"
			(at -0.95 -4.169 0)
			(layer "B.Fab")
			(effects
				(font
					(size 0.7 0.7)
					(thickness 0.15)
				)
				(justify left bottom mirror)
			)
		)
		(fp_text user "${REFERENCE}"
			(at -0.95 -3.168 0)
			(layer "B.Fab")
			(effects
				(font
					(size 0.7 0.7)
					(thickness 0.15)
				)
				(justify left bottom mirror)
			)
		)
		(fp_text user "License: Apache-2.0"
			(at -0.95 -5.169 0)
			(layer "B.Fab")
			(effects
				(font
					(size 0.7 0.7)
					(thickness 0.15)
				)
				(justify left bottom mirror)
			)
		)
		(pad "1" smd roundrect
			(at -0.48 0 180)
			(size 0.59 0.64)
			(layers "B.Cu" "B.Mask" "B.Paste")
			(roundrect_rratio 0.25)
			(net 417 "GND")
			(pintype "passive")
		)
		(pad "2" smd roundrect
			(at 0.48 0 180)
			(size 0.59 0.64)
			(layers "B.Cu" "B.Mask" "B.Paste")
			(roundrect_rratio 0.25)
			(net 289 "~{Crosslink_RESET}")
			(pintype "passive")
		)
	)
	(footprint "antmicro-footprints:C_0402_1005Metric"
		(layer "B.Cu")
		(at 223.9 147.295 90)
		(descr "Capacitor SMD 0402")
		(tags "capacitor SMD 0402")
		(property "Reference" "C230"
			(at -3.735 0.8 90)
			(layer "B.SilkS")
			(effects
				(font
					(size 0.7 0.7)
					(thickness 0.15)
				)
				(justify right bottom mirror)
			)
		)
		(property "Value" "C_100n_0402"
			(at -1.022927 -2.155213 90)
			(layer "B.Fab")
			(hide yes)
			(effects
				(font
					(size 0.7 0.7)
					(thickness 0.15)
				)
				(justify right bottom mirror)
			)
		)
		(property "Datasheet" "https://www.murata.com/products/productdetail?partno=GRM155R61H104KE14%23"
			(at 0 0 90)
			(layer "F.Fab")
			(hide yes)
			(effects
				(font
					(size 1.27 1.27)
					(thickness 0.15)
				)
			)
		)
		(property "Description" "SMD Multilayer Ceramic Capacitor, 0.1 µF, 50 V, 0402 [1005 Metric], ± 10%, X5R, GRM Series"
			(at 0 0 90)
			(layer "F.Fab")
			(hide yes)
			(effects
				(font
					(size 1.27 1.27)
					(thickness 0.15)
				)
			)
		)
		(property "Author" "Antmicro"
			(at 371.195 -76.605 0)
			(layer "B.Fab")
			(hide yes)
			(effects
				(font
					(size 1 1)
					(thickness 0.15)
				)
				(justify mirror)
			)
		)
		(property "Dielectric" "X5R"
			(at 371.195 -76.605 0)
			(layer "B.Fab")
			(hide yes)
			(effects
				(font
					(size 1 1)
					(thickness 0.15)
				)
				(justify mirror)
			)
		)
		(property "License" "Apache-2.0"
			(at 371.195 -76.605 0)
			(layer "B.Fab")
			(hide yes)
			(effects
				(font
					(size 1 1)
					(thickness 0.15)
				)
				(justify mirror)
			)
		)
		(property "MPN" "GRM155R61H104KE14D"
			(at 371.195 -76.605 0)
			(layer "B.Fab")
			(hide yes)
			(effects
				(font
					(size 1 1)
					(thickness 0.15)
				)
				(justify mirror)
			)
		)
		(property "Manufacturer" "Murata"
			(at 371.195 -76.605 0)
			(layer "B.Fab")
			(hide yes)
			(effects
				(font
					(size 1 1)
					(thickness 0.15)
				)
				(justify mirror)
			)
		)
		(property "Public" ""
			(at 371.195 -76.605 0)
			(layer "B.Fab")
			(hide yes)
			(effects
				(font
					(size 1 1)
					(thickness 0.15)
				)
				(justify mirror)
			)
		)
		(property "Val" "100n"
			(at 371.195 -76.605 0)
			(layer "B.Fab")
			(hide yes)
			(effects
				(font
					(size 1 1)
					(thickness 0.15)
				)
				(justify mirror)
			)
		)
		(property "Voltage" "50V"
			(at 371.195 -76.605 0)
			(layer "B.Fab")
			(hide yes)
			(effects
				(font
					(size 1 1)
					(thickness 0.15)
				)
				(justify mirror)
			)
		)
		(sheetname "/WiFi_Bluetooth/")
		(sheetfile "wifi_bt.kicad_sch")
		(attr smd)
		(fp_rect
			(start -0.925 0.47)
			(end 0.925 -0.47)
			(stroke
				(width 0.05)
				(type default)
			)
			(fill no)
			(layer "B.CrtYd")
		)
		(fp_line
			(start 0.504 -0.248)
			(end -0.494 -0.248)
			(stroke
				(width 0.15)
				(type solid)
			)
			(layer "B.Fab")
		)
		(fp_line
			(start -0.494 -0.248)
			(end -0.494 0.25)
			(stroke
				(width 0.15)
				(type solid)
			)
			(layer "B.Fab")
		)
		(fp_line
			(start 0.504 0.25)
			(end 0.504 -0.248)
			(stroke
				(width 0.15)
				(type solid)
			)
			(layer "B.Fab")
		)
		(fp_line
			(start -0.494 0.25)
			(end 0.504 0.25)
			(stroke
				(width 0.15)
				(type solid)
			)
			(layer "B.Fab")
		)
		(fp_text user "Author: Antmicro"
			(at -0.939 -3.399 270)
			(layer "B.Fab")
			(effects
				(font
					(size 0.7 0.7)
					(thickness 0.15)
				)
				(justify left bottom mirror)
			)
		)
		(fp_text user "${REFERENCE}"
			(at -0.939 -4.599 270)
			(layer "B.Fab")
			(effects
				(font
					(size 0.7 0.7)
					(thickness 0.15)
				)
				(justify left bottom mirror)
			)
		)
		(fp_text user "License: Apache-2.0"
			(at -0.939 -5.799 270)
			(layer "B.Fab")
			(effects
				(font
					(size 0.7 0.7)
					(thickness 0.15)
				)
				(justify left bottom mirror)
			)
		)
		(pad "1" smd roundrect
			(at -0.48 0 90)
			(size 0.59 0.64)
			(layers "B.Cu" "B.Mask" "B.Paste")
			(roundrect_rratio 0.25)
			(net 417 "GND")
			(pintype "passive")
		)
		(pad "2" smd roundrect
			(at 0.48 0 90)
			(size 0.59 0.64)
			(layers "B.Cu" "B.Mask" "B.Paste")
			(roundrect_rratio 0.25)
			(net 50 "+3V3")
			(pintype "passive")
		)
	)
)
